(kicad_pcb
	(version 20241229)
	(generator "pcbnew")
	(generator_version "9.0")
	(general
		(thickness 1.294)
		(legacy_teardrops no)
	)
	(paper "A3")
	(title_block
		(title "Kintex 410T devboard")
		(date "2024-04-03")
		(rev "1.1.2")
		(comment 9 "footprints 448-450 of 975")
	)
	(layers
		(0 "F.Cu" mixed)
		(4 "In1.Cu" power)
		(6 "In2.Cu" power)
		(8 "In3.Cu" mixed)
		(10 "In4.Cu" power)
		(12 "In5.Cu" mixed)
		(14 "In6.Cu" power)
		(16 "In7.Cu" mixed)
		(18 "In8.Cu" power)
		(2 "B.Cu" mixed)
		(9 "F.Adhes" user "F.Adhesive")
		(11 "B.Adhes" user "B.Adhesive")
		(13 "F.Paste" user)
		(15 "B.Paste" user)
		(5 "F.SilkS" user "F.Silkscreen")
		(7 "B.SilkS" user "B.Silkscreen")
		(1 "F.Mask" user)
		(3 "B.Mask" user)
		(17 "Dwgs.User" user "User.Drawings")
		(19 "Cmts.User" user "User.Comments")
		(21 "Eco1.User" user "User.Eco1")
		(23 "Eco2.User" user "User.Eco2")
		(25 "Edge.Cuts" user)
		(27 "Margin" user)
		(31 "F.CrtYd" user "F.Courtyard")
		(29 "B.CrtYd" user "B.Courtyard")
		(35 "F.Fab" user)
		(33 "B.Fab" user)
	)
	(footprint "antmicro-footprints:R_0402_1005Metric"
		(layer "F.Cu")
		(at 259.6 127.5 180)
		(descr "Resistor SMD 0402")
		(tags "resistor SMD 0402")
		(property "Reference" "R174"
			(at 1.05 5.75 180)
			(layer "F.SilkS")
			(effects
				(font
					(size 0.7 0.7)
					(thickness 0.15)
				)
				(justify left bottom)
			)
		)
		(property "Value" "R_33R_0402"
			(at 0 1.4 180)
			(layer "F.Fab")
			(effects
				(font
					(size 0.7 0.7)
					(thickness 0.15)
				)
				(justify left bottom)
			)
		)
		(property "Description" "SMD Chip Resistor, 33 ohm, ± 1%, 62.5 mW, 0402 [1005 Metric], Thick Film, General Purpose"
			(at 0 0 180)
			(layer "F.Fab")
			(hide yes)
			(effects
				(font
					(size 1.27 1.27)
					(thickness 0.15)
				)
			)
		)
		(property "Author" "Antmicro"
			(at 519.2 255 0)
			(layer "F.Fab")
			(hide yes)
			(effects
				(font
					(size 1 1)
					(thickness 0.15)
				)
			)
		)
		(property "License" "Apache-2.0"
			(at 519.2 255 0)
			(layer "F.Fab")
			(hide yes)
			(effects
				(font
					(size 1 1)
					(thickness 0.15)
				)
			)
		)
		(property "MPN" "CR0402-FX-33R0GLF"
			(at 519.2 255 0)
			(layer "F.Fab")
			(hide yes)
			(effects
				(font
					(size 1 1)
					(thickness 0.15)
				)
			)
		)
		(property "Manufacturer" "Bourns"
			(at 519.2 255 0)
			(layer "F.Fab")
			(hide yes)
			(effects
				(font
					(size 1 1)
					(thickness 0.15)
				)
			)
		)
		(property "Tolerance" "1%"
			(at 519.2 255 0)
			(layer "F.Fab")
			(hide yes)
			(effects
				(font
					(size 1 1)
					(thickness 0.15)
				)
			)
		)
		(property "Val" "33R"
			(at 519.2 255 0)
			(layer "F.Fab")
			(hide yes)
			(effects
				(font
					(size 1 1)
					(thickness 0.15)
				)
			)
		)
		(sheetname "USB PHY")
		(sheetfile "usb-phy.kicad_sch")
		(attr smd)
		(fp_rect
			(start -0.925 -0.47)
			(end 0.925 0.47)
			(stroke
				(width 0.05)
				(type default)
			)
			(fill no)
			(layer "F.CrtYd")
		)
		(fp_rect
			(start -0.5 -0.25)
			(end 0.5 0.25)
			(stroke
				(width 0.15)
				(type solid)
			)
			(fill no)
			(layer "F.Fab")
		)
		(pad "1" smd roundrect
			(at -0.48 0 180)
			(size 0.59 0.64)
			(layers "F.Cu" "F.Mask" "F.Paste")
			(roundrect_rratio 0.25)
			(net 842 "/USB PHY/USB_USR_CONN_D+")
			(pintype "passive")
		)
		(pad "2" smd roundrect
			(at 0.48 0 180)
			(size 0.59 0.64)
			(layers "F.Cu" "F.Mask" "F.Paste")
			(roundrect_rratio 0.25)
			(net 928 "/USB PHY/USB_USR_D+")
			(pintype "passive")
		)
	)
	(footprint "antmicro-footprints:LED_0603_1608Metric_G"
		(layer "F.Cu")
		(at 261.5 83.8)
		(descr "LED SMD 0603 Green")
		(tags "LED SMD 0603 Green")
		(property "Reference" "D18"
			(at -1.1 1.5 0)
			(layer "F.SilkS")
			(effects
				(font
					(size 0.7 0.7)
					(thickness 0.15)
				)
				(justify left bottom)
			)
		)
		(property "Value" "LED_G_0603_KP-1608CGCK"
			(at 0 1.6 0)
			(layer "F.Fab")
			(effects
				(font
					(size 0.7 0.7)
					(thickness 0.15)
				)
				(justify left bottom)
			)
		)
		(property "Description" "LED, Green, SMD, 0603, 20 mA, 2.1 V, 570 nm"
			(at 0 0 0)
			(layer "F.Fab")
			(hide yes)
			(effects
				(font
					(size 1.27 1.27)
					(thickness 0.15)
				)
			)
		)
		(property "Author" "Antmicro"
			(at 0 0 0)
			(layer "F.Fab")
			(hide yes)
			(effects
				(font
					(size 1 1)
					(thickness 0.15)
				)
			)
		)
		(property "Color" "Green"
			(at 0 0 0)
			(layer "F.Fab")
			(hide yes)
			(effects
				(font
					(size 1 1)
					(thickness 0.15)
				)
			)
		)
		(property "License" "Apache-2.0"
			(at 0 0 0)
			(layer "F.Fab")
			(hide yes)
			(effects
				(font
					(size 1 1)
					(thickness 0.15)
				)
			)
		)
		(property "MPN" "KP-1608CGCK"
			(at 0 0 0)
			(layer "F.Fab")
			(hide yes)
			(effects
				(font
					(size 1 1)
					(thickness 0.15)
				)
			)
		)
		(property "Manufacturer" "Kingbright"
			(at 0 0 0)
			(layer "F.Fab")
			(hide yes)
			(effects
				(font
					(size 1 1)
					(thickness 0.15)
				)
			)
		)
		(sheetname "User GPIO + LED + button + DIP switch")
		(sheetfile "user-gpio.kicad_sch")
		(attr smd)
		(fp_line
			(start -1.18 -0.319)
			(end -1.18 0.321)
			(stroke
				(width 0.15)
				(type solid)
			)
			(layer "F.SilkS")
		)
		(fp_line
			(start -0.094672 0.001008)
			(end -0.24 0.001008)
			(stroke
				(width 0.1)
				(type solid)
			)
			(layer "F.SilkS")
		)
		(fp_line
			(start -0.094672 0.001008)
			(end 0.105328 -0.198992)
			(stroke
				(width 0.1)
				(type solid)
			)
			(layer "F.SilkS")
		)
		(fp_line
			(start -0.094672 0.201008)
			(end -0.094672 -0.198992)
			(stroke
				(width 0.1)
				(type solid)
			)
			(layer "F.SilkS")
		)
		(fp_line
			(start 0.105328 0.001008)
			(end 0.24 0.001)
			(stroke
				(width 0.1)
				(type solid)
			)
			(layer "F.SilkS")
		)
		(fp_line
			(start 0.105328 0.201008)
			(end -0.094672 0.001008)
			(stroke
				(width 0.1)
				(type solid)
			)
			(layer "F.SilkS")
		)
		(fp_line
			(start 0.105328 0.201008)
			(end 0.105328 -0.198992)
			(stroke
				(width 0.1)
				(type solid)
			)
			(layer "F.SilkS")
		)
		(fp_line
			(start 0.22 -0.35)
			(end -0.22 -0.35)
			(stroke
				(width 0.15)
				(type solid)
			)
			(layer "F.SilkS")
		)
		(fp_line
			(start 0.22 0.35)
			(end -0.22 0.35)
			(stroke
				(width 0.15)
				(type solid)
			)
			(layer "F.SilkS")
		)
		(fp_rect
			(start 1.25 0.65)
			(end -1.25 -0.65)
			(stroke
				(width 0.05)
				(type solid)
			)
			(fill no)
			(layer "F.CrtYd")
		)
		(fp_line
			(start -0.199 -0.202)
			(end -0.199 0.1)
			(stroke
				(width 0.15)
				(type solid)
			)
			(layer "F.Fab")
		)
		(fp_line
			(start -0.199 0)
			(end -0.597 0)
			(stroke
				(width 0.15)
				(type solid)
			)
			(layer "F.Fab")
		)
		(fp_line
			(start -0.199 0.2)
			(end -0.199 0.1)
			(stroke
				(width 0.15)
				(type solid)
			)
			(layer "F.Fab")
		)
		(fp_line
			(start -0.101 0)
			(end 0.201 0.2)
			(stroke
				(width 0.15)
				(type solid)
			)
			(layer "F.Fab")
		)
		(fp_line
			(start 0.201 -0.202)
			(end -0.101 0)
			(stroke
				(width 0.15)
				(type solid)
			)
			(layer "F.Fab")
		)
		(fp_line
			(start 0.201 0)
			(end 0.201 -0.202)
			(stroke
				(width 0.15)
				(type solid)
			)
			(layer "F.Fab")
		)
		(fp_line
			(start 0.201 0.2)
			(end 0.201 0)
			(stroke
				(width 0.15)
				(type solid)
			)
			(layer "F.Fab")
		)
		(fp_line
			(start 0.599 0)
			(end 0.201 0)
			(stroke
				(width 0.15)
				(type solid)
			)
			(layer "F.Fab")
		)
		(fp_rect
			(start 0.848 0.4)
			(end -0.85 -0.402)
			(stroke
				(width 0.15)
				(type solid)
			)
			(fill no)
			(layer "F.Fab")
		)
		(pad "1" smd roundrect
			(at -0.7 0 180)
			(size 0.8 1)
			(layers "F.Cu" "F.Mask" "F.Paste")
			(roundrect_rratio 0.2)
			(net 772 "Net-(D18-C)")
			(pinfunction "C")
			(pintype "passive")
		)
		(pad "2" smd roundrect
			(at 0.7 0 180)
			(size 0.8 1)
			(layers "F.Cu" "F.Mask" "F.Paste")
			(roundrect_rratio 0.2)
			(net 775 "Net-(D18-A)")
			(pinfunction "A")
			(pintype "passive")
		)
	)
	(footprint "antmicro-footprints:PinHeader_2x20_P1.27mm_SMD_Shrouded"
		(layer "F.Cu")
		(at 233.002 96.576)
		(property "Reference" "J9"
			(at 14.748 -3.026 0)
			(layer "F.SilkS")
			(effects
				(font
					(size 0.7 0.7)
					(thickness 0.15)
				)
				(justify left bottom)
			)
		)
		(property "Value" "PinHeader_2x20_P1.27mm_SMD_Shrouded"
			(at -3.67 0.35 0)
			(layer "F.Fab")
			(effects
				(font
					(size 0.7 0.7)
					(thickness 0.15)
				)
				(justify left bottom)
			)
		)
		(property "Description" "Pin Header, Wire-to-Board, 1.27 mm, 2 Rows, 40 Contacts, Surface Mount Straight, WR-BHD Series"
			(at 0 0 0)
			(layer "F.Fab")
			(hide yes)
			(effects
				(font
					(size 1.27 1.27)
					(thickness 0.15)
				)
			)
		)
		(property "Author" "Antmicro"
			(at 0 0 0)
			(layer "F.Fab")
			(hide yes)
			(effects
				(font
					(size 1 1)
					(thickness 0.15)
				)
			)
		)
		(property "License" "Apache-2.0"
			(at 0 0 0)
			(layer "F.Fab")
			(hide yes)
			(effects
				(font
					(size 1 1)
					(thickness 0.15)
				)
			)
		)
		(property "MPN" "62704020621"
			(at 0 0 0)
			(layer "F.Fab")
			(hide yes)
			(effects
				(font
					(size 1 1)
					(thickness 0.15)
				)
			)
		)
		(property "Manufacturer" "Würth Elektronik"
			(at 0 0 0)
			(layer "F.Fab")
			(hide yes)
			(effects
				(font
					(size 1 1)
					(thickness 0.15)
				)
			)
		)
		(sheetname "User GPIO + LED + button + DIP switch")
		(sheetfile "user-gpio.kicad_sch")
		(attr smd)
		(fp_line
			(start -16 -2.6)
			(end -16 2.6)
			(stroke
				(width 0.15)
				(type solid)
			)
			(layer "F.SilkS")
		)
		(fp_line
			(start -16 -2.6)
			(end -12.7 -2.6)
			(stroke
				(width 0.15)
				(type solid)
			)
			(layer "F.SilkS")
		)
		(fp_line
			(start -16 2.6)
			(end -12.7 2.6)
			(stroke
				(width 0.15)
				(type solid)
			)
			(layer "F.SilkS")
		)
		(fp_line
			(start 12.7 -2.6)
			(end 16 -2.6)
			(stroke
				(width 0.15)
				(type solid)
			)
			(layer "F.SilkS")
		)
		(fp_line
			(start 12.7 2.6)
			(end 16 2.6)
			(stroke
				(width 0.15)
				(type solid)
			)
			(layer "F.SilkS")
		)
		(fp_line
			(start 16 -2.6)
			(end 16 2.6)
			(stroke
				(width 0.15)
				(type solid)
			)
			(layer "F.SilkS")
		)
		(fp_circle
			(center -12.77 3.1)
			(end -12.719 3.1)
			(stroke
				(width 0.15)
				(type solid)
			)
			(fill yes)
			(layer "F.SilkS")
		)
		(fp_rect
			(start -16.3 -3.5)
			(end 16.3 3.5)
			(stroke
				(width 0.05)
				(type solid)
			)
			(fill no)
			(layer "F.CrtYd")
		)
		(fp_line
			(start -15.87 2.59)
			(end -15.67 2.79)
			(stroke
				(width 0.15)
				(type solid)
			)
			(layer "F.Fab")
		)
		(fp_rect
			(start -15.875 -2.801)
			(end 15.874 2.798)
			(stroke
				(width 0.15)
				(type solid)
			)
			(fill no)
			(layer "F.Fab")
		)
		(pad "1" smd rect
			(at -12.065 1.999)
			(size 0.74 2.8)
			(layers "F.Cu" "F.Mask" "F.Paste")
			(net 1234 "/USER_IO.A1")
			(pintype "passive")
		)
		(pad "2" smd rect
			(at -12.065 -2)
			(size 0.74 2.8)
			(layers "F.Cu" "F.Mask" "F.Paste")
			(net 1 "GND")
			(pintype "passive")
		)
		(pad "3" smd rect
			(at -10.795 1.999)
			(size 0.74 2.8)
			(layers "F.Cu" "F.Mask" "F.Paste")
			(net 1235 "/USER_IO.A3")
			(pintype "passive")
		)
		(pad "4" smd rect
			(at -10.795 -2)
			(size 0.74 2.8)
			(layers "F.Cu" "F.Mask" "F.Paste")
			(net 1 "GND")
			(pintype "passive")
		)
		(pad "5" smd rect
			(at -9.526 1.999)
			(size 0.74 2.8)
			(layers "F.Cu" "F.Mask" "F.Paste")
			(net 1236 "/USER_IO.A5")
			(pintype "passive")
		)
		(pad "6" smd rect
			(at -9.526 -2)
			(size 0.74 2.8)
			(layers "F.Cu" "F.Mask" "F.Paste")
			(net 1 "GND")
			(pintype "passive")
		)
		(pad "7" smd rect
			(at -8.257 1.999)
			(size 0.74 2.8)
			(layers "F.Cu" "F.Mask" "F.Paste")
			(net 1237 "/USER_IO.A7")
			(pintype "passive")
		)
		(pad "8" smd rect
			(at -8.257 -2)
			(size 0.74 2.8)
			(layers "F.Cu" "F.Mask" "F.Paste")
			(net 1 "GND")
			(pintype "passive")
		)
		(pad "9" smd rect
			(at -6.986 1.999)
			(size 0.74 2.8)
			(layers "F.Cu" "F.Mask" "F.Paste")
			(net 1238 "/USER_IO.A9")
			(pintype "passive")
		)
		(pad "10" smd rect
			(at -6.986 -2)
			(size 0.74 2.8)
			(layers "F.Cu" "F.Mask" "F.Paste")
			(net 1 "GND")
			(pintype "passive")
		)
		(pad "11" smd rect
			(at -5.715 1.999)
			(size 0.74 2.8)
			(layers "F.Cu" "F.Mask" "F.Paste")
			(net 1239 "/USER_IO.A11")
			(pintype "passive")
		)
		(pad "12" smd rect
			(at -5.715 -2)
			(size 0.74 2.8)
			(layers "F.Cu" "F.Mask" "F.Paste")
			(net 1240 "/USER_IO.A12")
			(pintype "passive")
		)
		(pad "13" smd rect
			(at -4.446 1.999)
			(size 0.74 2.8)
			(layers "F.Cu" "F.Mask" "F.Paste")
			(net 1241 "/USER_IO.A13")
			(pintype "passive")
		)
		(pad "14" smd rect
			(at -4.446 -2)
			(size 0.74 2.8)
			(layers "F.Cu" "F.Mask" "F.Paste")
			(net 1242 "/USER_IO.A14")
			(pintype "passive")
		)
		(pad "15" smd rect
			(at -3.176 1.999)
			(size 0.74 2.8)
			(layers "F.Cu" "F.Mask" "F.Paste")
			(net 1243 "/USER_IO.A15")
			(pintype "passive")
		)
		(pad "16" smd rect
			(at -3.176 -2)
			(size 0.74 2.8)
			(layers "F.Cu" "F.Mask" "F.Paste")
			(net 1245 "/USER_IO.A16")
			(pintype "passive")
		)
		(pad "17" smd rect
			(at -1.905 1.999)
			(size 0.74 2.8)
			(layers "F.Cu" "F.Mask" "F.Paste")
			(net 1246 "/USER_IO.A17")
			(pintype "passive")
		)
		(pad "18" smd rect
			(at -1.905 -2)
			(size 0.74 2.8)
			(layers "F.Cu" "F.Mask" "F.Paste")
			(net 1247 "/USER_IO.A18")
			(pintype "passive")
		)
		(pad "19" smd rect
			(at -0.635 1.999)
			(size 0.74 2.8)
			(layers "F.Cu" "F.Mask" "F.Paste")
			(net 2 "VCC_USR_A")
			(pintype "passive")
		)
		(pad "20" smd rect
			(at -0.635 -2)
			(size 0.74 2.8)
			(layers "F.Cu" "F.Mask" "F.Paste")
			(net 1 "GND")
			(pintype "passive")
		)
		(pad "21" smd rect
			(at 0.633 1.999)
			(size 0.74 2.8)
			(layers "F.Cu" "F.Mask" "F.Paste")
			(net 1248 "/USER_IO.A21")
			(pintype "passive")
		)
		(pad "22" smd rect
			(at 0.633 -2)
			(size 0.74 2.8)
			(layers "F.Cu" "F.Mask" "F.Paste")
			(net 24 "+3V3")
			(pintype "passive")
		)
		(pad "23" smd rect
			(at 1.904 1.999)
			(size 0.74 2.8)
			(layers "F.Cu" "F.Mask" "F.Paste")
			(net 1249 "/USER_IO.A23")
			(pintype "passive")
		)
		(pad "24" smd rect
			(at 1.904 -2)
			(size 0.74 2.8)
			(layers "F.Cu" "F.Mask" "F.Paste")
			(net 1250 "/USER_IO.A24")
			(pintype "passive")
		)
		(pad "25" smd rect
			(at 3.173 1.999)
			(size 0.74 2.8)
			(layers "F.Cu" "F.Mask" "F.Paste")
			(net 1251 "/USER_IO.A25")
			(pintype "passive")
		)
		(pad "26" smd rect
			(at 3.173 -2)
			(size 0.74 2.8)
			(layers "F.Cu" "F.Mask" "F.Paste")
			(net 1252 "/USER_IO.A26")
			(pintype "passive")
		)
		(pad "27" smd rect
			(at 4.445 1.999)
			(size 0.74 2.8)
			(layers "F.Cu" "F.Mask" "F.Paste")
			(net 1253 "/USER_IO.A27")
			(pintype "passive")
		)
		(pad "28" smd rect
			(at 4.445 -2)
			(size 0.74 2.8)
			(layers "F.Cu" "F.Mask" "F.Paste")
			(net 1254 "/USER_IO.A28")
			(pintype "passive")
		)
		(pad "29" smd rect
			(at 5.714 1.999)
			(size 0.74 2.8)
			(layers "F.Cu" "F.Mask" "F.Paste")
			(net 1255 "/USER_IO.A29")
			(pintype "passive")
		)
		(pad "30" smd rect
			(at 5.714 -2)
			(size 0.74 2.8)
			(layers "F.Cu" "F.Mask" "F.Paste")
			(net 1256 "/USER_IO.A30")
			(pintype "passive")
		)
		(pad "31" smd rect
			(at 6.985 1.999)
			(size 0.74 2.8)
			(layers "F.Cu" "F.Mask" "F.Paste")
			(net 1257 "/USER_IO.A31")
			(pintype "passive")
		)
		(pad "32" smd rect
			(at 6.985 -2)
			(size 0.74 2.8)
			(layers "F.Cu" "F.Mask" "F.Paste")
			(net 1258 "/USER_IO.A32")
			(pintype "passive")
		)
		(pad "33" smd rect
			(at 8.255 1.999)
			(size 0.74 2.8)
			(layers "F.Cu" "F.Mask" "F.Paste")
			(net 1259 "/USER_IO.A33")
			(pintype "passive")
		)
		(pad "34" smd rect
			(at 8.255 -2)
			(size 0.74 2.8)
			(layers "F.Cu" "F.Mask" "F.Paste")
			(net 1 "GND")
			(pintype "passive")
		)
		(pad "35" smd rect
			(at 9.525 1.999)
			(size 0.74 2.8)
			(layers "F.Cu" "F.Mask" "F.Paste")
			(net 1260 "/USER_IO.A35")
			(pintype "passive")
		)
		(pad "36" smd rect
			(at 9.525 -2)
			(size 0.74 2.8)
			(layers "F.Cu" "F.Mask" "F.Paste")
			(net 1261 "/USER_IO.A36")
			(pintype "passive")
		)
		(pad "37" smd rect
			(at 10.794 1.999)
			(size 0.74 2.8)
			(layers "F.Cu" "F.Mask" "F.Paste")
			(net 1262 "/USER_IO.A37")
			(pintype "passive")
		)
		(pad "38" smd rect
			(at 10.794 -2)
			(size 0.74 2.8)
			(layers "F.Cu" "F.Mask" "F.Paste")
			(net 1263 "/USER_IO.A38")
			(pintype "passive")
		)
		(pad "39" smd rect
			(at 12.063 1.999)
			(size 0.74 2.8)
			(layers "F.Cu" "F.Mask" "F.Paste")
			(net 1264 "/USER_IO.A39")
			(pintype "passive")
		)
		(pad "40" smd rect
			(at 12.063 -2)
			(size 0.74 2.8)
			(layers "F.Cu" "F.Mask" "F.Paste")
			(net 1265 "/USER_IO.A40")
			(pintype "passive")
		)
	)
)
